(kicad_pcb
	(version 20260206)
	(generator "pcbnew")
	(generator_version "10.0")
	(general
		(thickness 1.6)
		(legacy_teardrops no)
	)
	(paper "A4")
	(title_block
		(title "Wiwynn_Tioga_Pass_MB.brd")
		(comment 1 "Tioga Pass / footprints 4559-4561 of 4770")
	)
	(layers
		(0 "F.Cu" signal "TOP")
		(4 "In1.Cu" signal "L2GND")
		(6 "In2.Cu" signal "L3")
		(8 "In3.Cu" signal "L4GND")
		(10 "In4.Cu" signal "L5")
		(12 "In5.Cu" signal "L6GND")
		(14 "In6.Cu" signal "L7VCC")
		(16 "In7.Cu" signal "L8VCC")
		(18 "In8.Cu" signal "L9GND")
		(20 "In9.Cu" signal "L10")
		(22 "In10.Cu" signal "L11GND")
		(24 "In11.Cu" signal "L12")
		(26 "In12.Cu" signal "L13GND")
		(2 "B.Cu" signal "BOTTOM")
		(9 "F.Adhes" user "F.Adhesive")
		(11 "B.Adhes" user "B.Adhesive")
		(13 "F.Paste" user "Package Geometry/Pastemask Top")
		(15 "B.Paste" user "Package Geometry/Pastemask Bottom")
		(5 "F.SilkS" user "Ref Des/Silkscreen Top")
		(7 "B.SilkS" user "Ref Des/Silkscreen Bottom")
		(1 "F.Mask" user "Board Geometry/Soldermask Top")
		(3 "B.Mask" user "Board Geometry/Soldermask Bottom")
		(17 "Dwgs.User" user "User.Drawings")
		(19 "Cmts.User" user "User.Comments")
		(21 "Eco1.User" user "User.Eco1")
		(23 "Eco2.User" user "User.Eco2")
		(25 "Edge.Cuts" user "Board Geometry/Outline")
		(27 "Margin" user)
		(31 "F.CrtYd" user "Package Geometry/Place Bound Top")
		(29 "B.CrtYd" user "Package Geometry/Place Bound Bottom")
		(35 "F.Fab" user "Ref Des/Assembly Top")
		(33 "B.Fab" user "Ref Des/Assembly Bottom")
	)
	(footprint ""
		(layer "B.Cu")
		(at 7.366 -63.56604 180)
		(property "Reference" "R9R1"
			(at -4.191 -1.48971 0)
			(unlocked yes)
			(layer "B.SilkS")
			(effects
				(font
					(size 0.7874 0.5842)
					(thickness 0.1524)
				)
				(justify left mirror)
			)
		)
		(property "Value" ""
			(at 0 0 0)
			(layer "B.Fab")
			(effects
				(font
					(size 1.27 1.27)
				)
				(justify mirror)
			)
		)
		(duplicate_pad_numbers_are_jumpers no)
		(fp_circle
			(center 2.29362 -0.691642)
			(end 2.16662 -0.691642)
			(stroke
				(width 0.254)
				(type default)
			)
			(fill no)
			(layer "B.SilkS")
		)
		(fp_rect
			(start 0.8001 3.11658)
			(end -5.8039 -0.31242)
			(stroke
				(width 0)
				(type default)
			)
			(fill no)
			(layer "B.CrtYd")
		)
		(fp_line
			(start 0.8001 3.11658)
			(end 0.8001 -0.31242)
			(stroke
				(width 0.1)
				(type default)
			)
			(layer "B.Fab")
		)
		(fp_line
			(start 0.8001 -0.31242)
			(end -5.8039 -0.31242)
			(stroke
				(width 0.1)
				(type default)
			)
			(layer "B.Fab")
		)
		(fp_line
			(start -5.8039 3.11658)
			(end 0.8001 3.11658)
			(stroke
				(width 0.1)
				(type default)
			)
			(layer "B.Fab")
		)
		(fp_line
			(start -5.8039 -0.31242)
			(end -5.8039 3.11658)
			(stroke
				(width 0.1)
				(type default)
			)
			(layer "B.Fab")
		)
		(fp_circle
			(center 1.740916 -1.623822)
			(end 1.613916 -1.623822)
			(stroke
				(width 0.254)
				(type default)
			)
			(fill no)
			(layer "B.Fab")
		)
		(pad "1" smd rect
			(at 0 0)
			(size 3.4036 1.1938)
			(layers "B.Cu" "B.Mask" "B.Paste")
			(net "P12V_PSU")
		)
		(pad "2" smd rect
			(at -5.0038 0)
			(size 3.4036 1.1938)
			(layers "B.Cu" "B.Mask" "B.Paste")
			(net "P12V_MB0_SW")
		)
		(pad "3" smd rect
			(at 0 1.40208)
			(size 3.4036 0.6096)
			(layers "B.Cu" "B.Mask" "B.Paste")
			(net "P12V_HSC_SENP1")
		)
		(pad "4" smd rect
			(at -5.0038 1.40208)
			(size 3.4036 0.6096)
			(layers "B.Cu" "B.Mask" "B.Paste")
			(net "P12V_HSC_SENN1")
		)
		(pad "5" smd rect
			(at 0 2.80416)
			(size 3.4036 1.1938)
			(layers "B.Cu" "B.Mask" "B.Paste")
			(net "P12V_PSU")
		)
		(pad "6" smd rect
			(at -5.0038 2.80416)
			(size 3.4036 1.1938)
			(layers "B.Cu" "B.Mask" "B.Paste")
			(net "P12V_MB0_SW")
		)
		(zone
			(layer "B.Cu")
			(hatch none 0.5)
			(connect_pads
				(clearance 0)
			)
			(min_thickness 0.25)
			(keepout
				(tracks allowed)
				(vias not_allowed)
				(pads allowed)
				(copperpour not_allowed)
				(footprints allowed)
			)
			(placement
				(enabled no)
				(sheetname "")
			)
			(fill
				(thermal_gap 0.5)
				(thermal_bridge_width 0.5)
				(island_removal_mode 0)
			)
			(polygon
				(pts
					(xy 9.0678 -63.17996) (xy 9.0678 -66.9671) (xy 10.668 -66.9671) (xy 10.668 -62.96914) (xy 9.11352 -62.96914)
					(xy 9.0678 -62.96914)
				)
			)
		)
	)
	(footprint ""
		(layer "B.Cu")
		(at 181.0004 -77.1144 -90)
		(property "Reference" "R6P16"
			(at 0 0 90)
			(layer "B.SilkS")
			(hide yes)
			(effects
				(font
					(size 1.27 1.27)
				)
				(justify mirror)
			)
		)
		(property "Value" ""
			(at 0 0 90)
			(layer "B.Fab")
			(effects
				(font
					(size 1.27 1.27)
				)
				(justify mirror)
			)
		)
		(duplicate_pad_numbers_are_jumpers no)
		(fp_poly
			(pts
				(xy 0.2794 -0.1016) (xy -0.2794 -0.1016) (xy -0.2794 0.9906) (xy 0.2794 0.9906)
			)
			(stroke
				(width 0)
				(type default)
			)
			(fill no)
			(layer "B.CrtYd")
		)
		(fp_line
			(start -0.2794 0.9906)
			(end -0.2794 -0.1016)
			(stroke
				(width 0.1)
				(type default)
			)
			(layer "B.Fab")
		)
		(fp_line
			(start 0.2794 0.9906)
			(end -0.2794 0.9906)
			(stroke
				(width 0.1)
				(type default)
			)
			(layer "B.Fab")
		)
		(fp_line
			(start -0.2794 -0.1016)
			(end 0.2794 -0.1016)
			(stroke
				(width 0.1)
				(type default)
			)
			(layer "B.Fab")
		)
		(fp_line
			(start 0.2794 -0.1016)
			(end 0.2794 0.9906)
			(stroke
				(width 0.1)
				(type default)
			)
			(layer "B.Fab")
		)
		(pad "1" smd rect
			(at 0 0 90)
			(size 0.508 0.508)
			(layers "B.Cu" "B.Mask" "B.Paste")
			(net "PVCCIO_CPU0")
		)
		(pad "2" smd rect
			(at 0 0.889 90)
			(size 0.508 0.508)
			(layers "B.Cu" "B.Mask" "B.Paste")
			(net "VR_PVCCIN_CPU0_VREN")
		)
		(zone
			(layer "B.Cu")
			(hatch none 0.5)
			(connect_pads
				(clearance 0)
			)
			(min_thickness 0.25)
			(keepout
				(tracks not_allowed)
				(vias allowed)
				(pads allowed)
				(copperpour not_allowed)
				(footprints allowed)
			)
			(placement
				(enabled no)
				(sheetname "")
			)
			(fill
				(thermal_gap 0.5)
				(thermal_bridge_width 0.5)
				(island_removal_mode 0)
			)
			(polygon
				(pts
					(xy 180.3654 -76.8604) (xy 180.3654 -77.3684) (xy 180.7464 -77.3684) (xy 180.7464 -76.8604)
				)
			)
		)
		(zone
			(layer "B.Cu")
			(hatch none 0.5)
			(connect_pads
				(clearance 0)
			)
			(min_thickness 0.25)
			(keepout
				(tracks allowed)
				(vias not_allowed)
				(pads allowed)
				(copperpour not_allowed)
				(footprints allowed)
			)
			(placement
				(enabled no)
				(sheetname "")
			)
			(fill
				(thermal_gap 0.5)
				(thermal_bridge_width 0.5)
				(island_removal_mode 0)
			)
			(polygon
				(pts
					(xy 180.7464 -76.8604) (xy 180.7464 -77.3684) (xy 180.3654 -77.3684) (xy 180.3654 -76.8604)
				)
			)
		)
	)
	(footprint ""
		(layer "B.Cu")
		(at 17.9832 -8.9662 -90)
		(property "Reference" "C9U5"
			(at -2.00533 9.271 0)
			(unlocked yes)
			(layer "B.SilkS")
			(effects
				(font
					(size 0.7874 0.5842)
					(thickness 0.1524)
				)
				(justify mirror)
			)
		)
		(property "Value" ""
			(at 0 0 90)
			(layer "B.Fab")
			(effects
				(font
					(size 1.27 1.27)
				)
				(justify mirror)
			)
		)
		(duplicate_pad_numbers_are_jumpers no)
		(fp_line
			(start -2.286 7.366)
			(end -1.600708 7.366)
			(stroke
				(width 0.1524)
				(type default)
			)
			(layer "B.SilkS")
		)
		(fp_line
			(start -2.286 7.366)
			(end -2.286 1.63195)
			(stroke
				(width 0.1524)
				(type default)
			)
			(layer "B.SilkS")
		)
		(fp_line
			(start 2.286 7.366)
			(end 1.60147 7.366)
			(stroke
				(width 0.1524)
				(type default)
			)
			(layer "B.SilkS")
		)
		(fp_line
			(start 2.286 7.366)
			(end 2.286 1.632712)
			(stroke
				(width 0.1524)
				(type default)
			)
			(layer "B.SilkS")
		)
		(fp_line
			(start -2.504948 1.633728)
			(end -1.6002 1.633728)
			(stroke
				(width 0.1524)
				(type default)
			)
			(layer "B.SilkS")
		)
		(fp_line
			(start 2.563114 1.633728)
			(end 1.6002 1.633728)
			(stroke
				(width 0.1524)
				(type default)
			)
			(layer "B.SilkS")
		)
		(fp_line
			(start -2.504948 -1.616456)
			(end -2.504948 1.633728)
			(stroke
				(width 0.1524)
				(type default)
			)
			(layer "B.SilkS")
		)
		(fp_line
			(start -1.6002 -1.616456)
			(end -2.504948 -1.616456)
			(stroke
				(width 0.1524)
				(type default)
			)
			(layer "B.SilkS")
		)
		(fp_line
			(start 1.6002 -1.616456)
			(end 2.563114 -1.616456)
			(stroke
				(width 0.1524)
				(type default)
			)
			(layer "B.SilkS")
		)
		(fp_line
			(start 2.563114 -1.616456)
			(end 2.563114 1.633728)
			(stroke
				(width 0.1524)
				(type default)
			)
			(layer "B.SilkS")
		)
		(fp_rect
			(start 2.286 -0.254)
			(end -2.286 7.366)
			(stroke
				(width 0)
				(type default)
			)
			(fill no)
			(layer "B.CrtYd")
		)
		(fp_line
			(start -2.286 7.366)
			(end 2.286 7.366)
			(stroke
				(width 0.1)
				(type default)
			)
			(layer "B.Fab")
		)
		(fp_line
			(start 2.286 7.366)
			(end 2.286 -0.254)
			(stroke
				(width 0.1)
				(type default)
			)
			(layer "B.Fab")
		)
		(fp_line
			(start -2.286 -0.254)
			(end -2.286 7.366)
			(stroke
				(width 0.1)
				(type default)
			)
			(layer "B.Fab")
		)
		(fp_line
			(start 2.286 -0.254)
			(end -2.286 -0.254)
			(stroke
				(width 0.1)
				(type default)
			)
			(layer "B.Fab")
		)
		(pad "1" smd rect
			(at 0 0 90)
			(size 2.54 3.048)
			(layers "B.Cu" "B.Mask" "B.Paste")
			(net "PVDDQ_GHJ")
		)
		(pad "2" smd rect
			(at 0 7.112 90)
			(size 2.54 3.048)
			(layers "B.Cu" "B.Mask" "B.Paste")
			(net "GND")
		)
	)
)
